(kicad_pcb
	(version 20260206)
	(generator "pcbnew")
	(generator_version "10.0")
	(general
		(thickness 1.6)
		(legacy_teardrops no)
	)
	(paper "A4")
	(title_block
		(title "Bryce Canyon_R.DPB_16317-1_OCP.brd")
		(comment 1 "Bryce Canyon / footprints 2005-2012 of 2099")
	)
	(layers
		(0 "F.Cu" signal "TOP")
		(4 "In1.Cu" signal "L2GND")
		(6 "In2.Cu" signal "L3")
		(8 "In3.Cu" signal "L4VCC")
		(10 "In4.Cu" signal "L5VCC")
		(12 "In5.Cu" signal "L6")
		(14 "In6.Cu" signal "L7GND")
		(2 "B.Cu" signal "BOTTOM")
		(9 "F.Adhes" user "F.Adhesive")
		(11 "B.Adhes" user "B.Adhesive")
		(13 "F.Paste" user "Package Geometry/Pastemask Top")
		(15 "B.Paste" user "Package Geometry/Pastemask Bottom")
		(5 "F.SilkS" user "Ref Des/Silkscreen Top")
		(7 "B.SilkS" user "Ref Des/Silkscreen Bottom")
		(1 "F.Mask" user "Board Geometry/Soldermask Top")
		(3 "B.Mask" user "Board Geometry/Soldermask Bottom")
		(17 "Dwgs.User" user "User.Drawings")
		(19 "Cmts.User" user "User.Comments")
		(21 "Eco1.User" user "User.Eco1")
		(23 "Eco2.User" user "User.Eco2")
		(25 "Edge.Cuts" user "Board Geometry/Outline")
		(27 "Margin" user)
		(31 "F.CrtYd" user "Package Geometry/Place Bound Top")
		(29 "B.CrtYd" user "Package Geometry/Place Bound Bottom")
		(35 "F.Fab" user "Ref Des/Assembly Top")
		(33 "B.Fab" user "Ref Des/Assembly Bottom")
	)
	(footprint ""
		(layer "B.Cu")
		(at 213.995 -355.473 180)
		(property "Reference" "C511"
			(at 0 0 0)
			(layer "B.SilkS")
			(hide yes)
			(effects
				(font
					(size 1.27 1.27)
				)
				(justify mirror)
			)
		)
		(property "Value" "SC22U25V6KX-2-GP-U"
			(at 2.860802 -5.279644 180)
			(unlocked yes)
			(layer "B.Fab")
			(hide yes)
			(effects
				(font
					(size 1.016 1.016)
					(thickness 0.1524)
				)
				(justify mirror)
			)
		)
		(property "Device Type" "C1206-TO0D3H75"
			(at 2.860802 -6.803644 180)
			(unlocked yes)
			(layer "B.Fab")
			(hide yes)
			(effects
				(font
					(size 1.016 1.016)
					(thickness 0.1524)
				)
				(justify mirror)
			)
		)
		(duplicate_pad_numbers_are_jumpers no)
		(fp_line
			(start 1.3081 2.3749)
			(end 1.3081 -2.3749)
			(stroke
				(width 0.1524)
				(type default)
			)
			(layer "B.SilkS")
		)
		(fp_line
			(start 1.3081 -2.3749)
			(end -1.3081 -2.3749)
			(stroke
				(width 0.1524)
				(type default)
			)
			(layer "B.SilkS")
		)
		(fp_line
			(start -1.3081 2.3749)
			(end 1.3081 2.3749)
			(stroke
				(width 0.1524)
				(type default)
			)
			(layer "B.SilkS")
		)
		(fp_line
			(start -1.3081 -2.3749)
			(end -1.3081 2.3749)
			(stroke
				(width 0.1524)
				(type default)
			)
			(layer "B.SilkS")
		)
		(fp_rect
			(start 0.8001 1.6002)
			(end -0.8001 -1.6002)
			(stroke
				(width 0)
				(type default)
			)
			(fill no)
			(layer "B.CrtYd")
		)
		(fp_poly
			(pts
				(xy 1.5621 2.4511) (xy 1.5621 1.6002) (xy -0.8001 1.6002) (xy -0.8001 -1.6002) (xy 0.8001 -1.6002)
				(xy 0.8001 1.5875) (xy 1.5621 1.5875) (xy 1.5621 -2.4511) (xy -1.5621 -2.4511) (xy -1.5621 2.4511)
			)
			(stroke
				(width 0)
				(type default)
			)
			(fill no)
			(layer "B.CrtYd")
		)
		(fp_rect
			(start 1.5621 2.4511)
			(end -1.5621 -2.4511)
			(stroke
				(width 0)
				(type default)
			)
			(fill no)
			(layer "B.Fab")
		)
		(pad "1" smd rect
			(at 0 -1.392936)
			(size 2.1082 1.4478)
			(layers "B.Cu" "B.Mask" "B.Paste")
			(net "P12V_IN")
		)
		(pad "2" smd rect
			(at 0 1.392936)
			(size 2.1082 1.4478)
			(layers "B.Cu" "B.Mask" "B.Paste")
			(net "GND")
		)
	)
	(footprint ""
		(layer "B.Cu")
		(at 50.104802 -228.22535 -90)
		(property "Reference" "G1"
			(at 0 0 90)
			(layer "B.SilkS")
			(hide yes)
			(effects
				(font
					(size 1.27 1.27)
				)
				(justify mirror)
			)
		)
		(property "Value" "GAP-CLOSE-PWR-4-GP"
			(at 2.4638 -0.5461 270)
			(unlocked yes)
			(layer "B.Fab")
			(hide yes)
			(effects
				(font
					(size 1.016 1.016)
					(thickness 0.1524)
				)
				(justify mirror)
			)
		)
		(property "Device Type" "GAP-CLOSE-PWR-4"
			(at 2.4638 -2.0701 270)
			(unlocked yes)
			(layer "B.Fab")
			(hide yes)
			(effects
				(font
					(size 1.016 1.016)
					(thickness 0.1524)
				)
				(justify mirror)
			)
		)
		(duplicate_pad_numbers_are_jumpers no)
		(fp_rect
			(start 0.2794 0.254)
			(end -0.2794 -0.254)
			(stroke
				(width 0)
				(type default)
			)
			(fill no)
			(layer "B.CrtYd")
		)
		(fp_rect
			(start 0.2794 0.254)
			(end -0.2794 -0.254)
			(stroke
				(width 0)
				(type default)
			)
			(fill no)
			(layer "B.Fab")
		)
		(pad "1" smd rect
			(at 0.0635 0 90)
			(size 0.1778 0.254)
			(layers "B.Cu" "B.Mask" "B.Paste")
			(net "P5V_B_1")
		)
		(pad "2" smd rect
			(at -0.0635 0 90)
			(size 0.1778 0.254)
			(layers "B.Cu" "B.Mask" "B.Paste")
			(net "P5V_B_1_CC")
		)
	)
	(footprint ""
		(layer "B.Cu")
		(at 457.833984 -119.727218 180)
		(property "Reference" "TC8"
			(at 0 0 0)
			(layer "B.SilkS")
			(hide yes)
			(effects
				(font
					(size 1.27 1.27)
				)
				(justify mirror)
			)
		)
		(property "Value" "ST220U10VDM-LGP"
			(at 0 -9.6012 180)
			(unlocked yes)
			(layer "B.Fab")
			(hide yes)
			(effects
				(font
					(size 1.016 1.016)
					(thickness 0.1524)
				)
				(justify mirror)
			)
		)
		(property "Device Type" "CT7343H119"
			(at 0 -11.1252 180)
			(unlocked yes)
			(layer "B.Fab")
			(hide yes)
			(effects
				(font
					(size 1.016 1.016)
					(thickness 0.1524)
				)
				(justify mirror)
			)
		)
		(duplicate_pad_numbers_are_jumpers no)
		(fp_line
			(start 2.286 4.8768)
			(end 2.286 2.032)
			(stroke
				(width 0.1524)
				(type default)
			)
			(layer "B.SilkS")
		)
		(fp_line
			(start 2.286 -4.8768)
			(end 2.286 -2.032)
			(stroke
				(width 0.1524)
				(type default)
			)
			(layer "B.SilkS")
		)
		(fp_line
			(start -2.1082 -4.699)
			(end 2.1082 -4.699)
			(stroke
				(width 0.508)
				(type default)
			)
			(layer "B.SilkS")
		)
		(fp_line
			(start -2.286 4.8768)
			(end 2.286 4.8768)
			(stroke
				(width 0.1524)
				(type default)
			)
			(layer "B.SilkS")
		)
		(fp_line
			(start -2.286 2.032)
			(end -2.286 4.8768)
			(stroke
				(width 0.1524)
				(type default)
			)
			(layer "B.SilkS")
		)
		(fp_line
			(start -2.286 -2.032)
			(end -2.286 -4.8768)
			(stroke
				(width 0.1524)
				(type default)
			)
			(layer "B.SilkS")
		)
		(fp_line
			(start -2.286 -4.8768)
			(end 2.286 -4.8768)
			(stroke
				(width 0.1524)
				(type default)
			)
			(layer "B.SilkS")
		)
		(fp_rect
			(start 2.1463 3.6449)
			(end -2.1463 -3.6449)
			(stroke
				(width 0)
				(type default)
			)
			(fill no)
			(layer "B.CrtYd")
		)
		(fp_poly
			(pts
				(xy 2.54 4.953) (xy 2.54 4.2926) (xy 3.81 4.2926) (xy 3.81 -4.2926) (xy 2.54 -4.2926) (xy 2.54 -4.953)
				(xy -2.54 -4.953) (xy -2.54 -4.2926) (xy -3.81 -4.2926) (xy -3.81 -1.6256) (xy -2.1463 -1.6256)
				(xy -2.1463 -3.6449) (xy 2.1463 -3.6449) (xy 2.1463 3.6449) (xy -2.1463 3.6449) (xy -2.1463 -1.6129)
				(xy -3.81 -1.6129) (xy -3.81 4.2926) (xy -2.54 4.2926) (xy -2.54 4.953)
			)
			(stroke
				(width 0)
				(type default)
			)
			(fill no)
			(layer "B.CrtYd")
		)
		(fp_rect
			(start 3.81 4.2926)
			(end 2.54 -4.2926)
			(stroke
				(width 0)
				(type default)
			)
			(fill no)
			(layer "B.Fab")
		)
		(fp_rect
			(start 2.54 4.953)
			(end -2.54 -4.953)
			(stroke
				(width 0)
				(type default)
			)
			(fill no)
			(layer "B.Fab")
		)
		(fp_rect
			(start -2.54 4.2926)
			(end -3.81 -4.2926)
			(stroke
				(width 0)
				(type default)
			)
			(fill no)
			(layer "B.Fab")
		)
		(pad "1" smd rect
			(at 0 -3.1496)
			(size 2.413 2.286)
			(layers "B.Cu" "B.Mask" "B.Paste")
			(net "P5V_B_4")
		)
		(pad "2" smd rect
			(at 0 3.1496)
			(size 2.413 2.286)
			(layers "B.Cu" "B.Mask" "B.Paste")
			(net "GND")
		)
		(zone
			(layer "B.Cu")
			(hatch none 0.5)
			(connect_pads
				(clearance 0)
			)
			(min_thickness 0.25)
			(keepout
				(tracks allowed)
				(vias not_allowed)
				(pads allowed)
				(copperpour not_allowed)
				(footprints allowed)
			)
			(placement
				(enabled no)
				(sheetname "")
			)
			(fill
				(thermal_gap 0.5)
				(thermal_bridge_width 0.5)
				(island_removal_mode 0)
			)
			(polygon
				(pts
					(xy 456.322684 -124.324618) (xy 459.345284 -124.324618) (xy 459.345284 -121.429018) (xy 459.345284 -121.098818)
					(xy 456.322684 -121.098818) (xy 456.322684 -121.429018)
				)
			)
		)
		(zone
			(layer "B.Cu")
			(hatch none 0.5)
			(connect_pads
				(clearance 0)
			)
			(min_thickness 0.25)
			(keepout
				(tracks allowed)
				(vias not_allowed)
				(pads allowed)
				(copperpour not_allowed)
				(footprints allowed)
			)
			(placement
				(enabled no)
				(sheetname "")
			)
			(fill
				(thermal_gap 0.5)
				(thermal_bridge_width 0.5)
				(island_removal_mode 0)
			)
			(polygon
				(pts
					(xy 459.345284 -118.038118) (xy 459.345284 -115.129818) (xy 456.322684 -115.129818) (xy 456.322684 -118.025418)
					(xy 456.322684 -118.355618) (xy 459.345284 -118.355618)
				)
			)
		)
	)
	(footprint ""
		(layer "B.Cu")
		(at 259.388864 -289.641534)
		(property "Reference" "R1176"
			(at 0 0 0)
			(layer "B.SilkS")
			(hide yes)
			(effects
				(font
					(size 1.27 1.27)
				)
				(justify mirror)
			)
		)
		(property "Value" "10R3F-GP"
			(at 0.0254 -2.5146 0)
			(unlocked yes)
			(layer "B.Fab")
			(hide yes)
			(effects
				(font
					(size 1.016 1.016)
					(thickness 0.1524)
				)
				(justify mirror)
			)
		)
		(property "Device Type" "R603H22"
			(at 0.0254 -4.0386 0)
			(unlocked yes)
			(layer "B.Fab")
			(hide yes)
			(effects
				(font
					(size 1.016 1.016)
					(thickness 0.1524)
				)
				(justify mirror)
			)
		)
		(duplicate_pad_numbers_are_jumpers no)
		(fp_line
			(start -0.2032 0)
			(end -0.4826 0)
			(stroke
				(width 0.2032)
				(type default)
			)
			(layer "B.SilkS")
		)
		(fp_line
			(start 0.4826 0)
			(end 0.2032 0)
			(stroke
				(width 0.2032)
				(type default)
			)
			(layer "B.SilkS")
		)
		(fp_rect
			(start 0.5842 1.3335)
			(end -0.5842 -1.3335)
			(stroke
				(width 0)
				(type default)
			)
			(fill no)
			(layer "B.CrtYd")
		)
		(fp_rect
			(start 0.5842 1.3335)
			(end -0.5842 -1.3335)
			(stroke
				(width 0)
				(type default)
			)
			(fill no)
			(layer "B.Fab")
		)
		(pad "1" smd custom
			(at 0 -0.762 180)
			(size 0.2159 0.2159)
			(layers "B.Cu" "B.Mask" "B.Paste")
			(net "P3V3_STBY_CC")
			(options
				(clearance outline)
				(anchor circle)
			)
			(primitives
				(gr_poly
					(pts
						(arc
							(start -0.3302 0.4318)
							(mid -0.402042 0.402042)
							(end -0.4318 0.3302)
						)
						(arc
							(start -0.4318 -0.3302)
							(mid -0.402042 -0.402042)
							(end -0.3302 -0.4318)
						)
						(arc
							(start 0.3302 -0.4318)
							(mid 0.402042 -0.402042)
							(end 0.4318 -0.3302)
						)
						(arc
							(start 0.4318 0.3302)
							(mid 0.402042 0.402042)
							(end 0.3302 0.4318)
						)
					)
					(width 0)
					(fill yes)
				)
			)
		)
		(pad "2" smd custom
			(at 0 0.762 180)
			(size 0.2159 0.2159)
			(layers "B.Cu" "B.Mask" "B.Paste")
			(net "P3V3_STBY_CC_R")
			(options
				(clearance outline)
				(anchor circle)
			)
			(primitives
				(gr_poly
					(pts
						(arc
							(start -0.3302 0.4318)
							(mid -0.402042 0.402042)
							(end -0.4318 0.3302)
						)
						(arc
							(start -0.4318 -0.3302)
							(mid -0.402042 -0.402042)
							(end -0.3302 -0.4318)
						)
						(arc
							(start 0.3302 -0.4318)
							(mid 0.402042 -0.402042)
							(end 0.4318 -0.3302)
						)
						(arc
							(start 0.4318 0.3302)
							(mid 0.402042 0.402042)
							(end 0.3302 0.4318)
						)
					)
					(width 0)
					(fill yes)
				)
			)
		)
	)
	(footprint ""
		(layer "B.Cu")
		(at 253.873 -279.146 90)
		(property "Reference" "C707"
			(at 0 0 90)
			(layer "B.SilkS")
			(hide yes)
			(effects
				(font
					(size 1.27 1.27)
				)
				(justify mirror)
			)
		)
		(property "Value" "SC1U16V3KX-5GP"
			(at 0 -2.8194 90)
			(unlocked yes)
			(layer "B.Fab")
			(hide yes)
			(effects
				(font
					(size 1.016 1.016)
					(thickness 0.1524)
				)
				(justify mirror)
			)
		)
		(property "Device Type" "C603H36"
			(at 0 -4.3434 90)
			(unlocked yes)
			(layer "B.Fab")
			(hide yes)
			(effects
				(font
					(size 1.016 1.016)
					(thickness 0.1524)
				)
				(justify mirror)
			)
		)
		(duplicate_pad_numbers_are_jumpers no)
		(fp_line
			(start -0.508 0)
			(end 0.508 0)
			(stroke
				(width 0.2032)
				(type default)
			)
			(layer "B.SilkS")
		)
		(fp_rect
			(start 0.5842 1.3335)
			(end -0.5842 -1.3335)
			(stroke
				(width 0)
				(type default)
			)
			(fill no)
			(layer "B.CrtYd")
		)
		(fp_rect
			(start 0.5842 1.3335)
			(end -0.5842 -1.3335)
			(stroke
				(width 0)
				(type default)
			)
			(fill no)
			(layer "B.Fab")
		)
		(pad "1" smd custom
			(at 0 -0.762 270)
			(size 0.2159 0.2159)
			(layers "B.Cu" "B.Mask" "B.Paste")
			(net "GND")
			(options
				(clearance outline)
				(anchor circle)
			)
			(primitives
				(gr_poly
					(pts
						(arc
							(start -0.3302 0.4318)
							(mid -0.402042 0.402042)
							(end -0.4318 0.3302)
						)
						(arc
							(start -0.4318 -0.3302)
							(mid -0.402042 -0.402042)
							(end -0.3302 -0.4318)
						)
						(arc
							(start 0.3302 -0.4318)
							(mid 0.402042 -0.402042)
							(end 0.4318 -0.3302)
						)
						(arc
							(start 0.4318 0.3302)
							(mid 0.402042 0.402042)
							(end 0.3302 0.4318)
						)
					)
					(width 0)
					(fill yes)
				)
			)
		)
		(pad "2" smd custom
			(at 0 0.762 270)
			(size 0.2159 0.2159)
			(layers "B.Cu" "B.Mask" "B.Paste")
			(net "P3V3_STBY_EN_R")
			(options
				(clearance outline)
				(anchor circle)
			)
			(primitives
				(gr_poly
					(pts
						(arc
							(start -0.3302 0.4318)
							(mid -0.402042 0.402042)
							(end -0.4318 0.3302)
						)
						(arc
							(start -0.4318 -0.3302)
							(mid -0.402042 -0.402042)
							(end -0.3302 -0.4318)
						)
						(arc
							(start 0.3302 -0.4318)
							(mid 0.402042 -0.402042)
							(end 0.4318 -0.3302)
						)
						(arc
							(start 0.4318 0.3302)
							(mid 0.402042 0.402042)
							(end 0.3302 0.4318)
						)
					)
					(width 0)
					(fill yes)
				)
			)
		)
	)
	(footprint ""
		(layer "B.Cu")
		(at 251.714 -288.671 -90)
		(property "Reference" "C691"
			(at 0 0 90)
			(layer "B.SilkS")
			(hide yes)
			(effects
				(font
					(size 1.27 1.27)
				)
				(justify mirror)
			)
		)
		(property "Value" "SC10U16V5KX-7-GP-U"
			(at 0.0762 -6.1214 270)
			(unlocked yes)
			(layer "B.Fab")
			(hide yes)
			(effects
				(font
					(size 1.016 1.016)
					(thickness 0.1524)
				)
				(justify mirror)
			)
		)
		(property "Device Type" "C805H58"
			(at 0.0762 -8.1534 270)
			(unlocked yes)
			(layer "B.Fab")
			(hide yes)
			(effects
				(font
					(size 1.016 1.016)
					(thickness 0.1524)
				)
				(justify mirror)
			)
		)
		(duplicate_pad_numbers_are_jumpers no)
		(fp_line
			(start -0.635 0)
			(end 0.635 0)
			(stroke
				(width 0.508)
				(type default)
			)
			(layer "B.SilkS")
		)
		(fp_rect
			(start 0.9652 1.778)
			(end -0.9652 -1.778)
			(stroke
				(width 0)
				(type default)
			)
			(fill no)
			(layer "B.CrtYd")
		)
		(fp_poly
			(pts
				(xy 0.9652 -1.778) (xy -0.9652 -1.778) (xy -0.9652 1.778) (xy 0.9652 1.778)
			)
			(stroke
				(width 0)
				(type default)
			)
			(fill no)
			(layer "B.Fab")
		)
		(pad "1" smd rect
			(at 0 -0.9652 90)
			(size 1.397 1.143)
			(layers "B.Cu" "B.Mask" "B.Paste")
			(net "P3V3_STBY_VIN")
		)
		(pad "2" smd rect
			(at 0 0.9652 90)
			(size 1.397 1.143)
			(layers "B.Cu" "B.Mask" "B.Paste")
			(net "GND")
		)
	)
	(footprint ""
		(layer "B.Cu")
		(at 431.129186 -112.701578 180)
		(property "Reference" "C671"
			(at 0 0 0)
			(layer "B.SilkS")
			(hide yes)
			(effects
				(font
					(size 1.27 1.27)
				)
				(justify mirror)
			)
		)
		(property "Value" "SC10U16V5KX-7-GP-U"
			(at 0.0762 -6.1214 180)
			(unlocked yes)
			(layer "B.Fab")
			(hide yes)
			(effects
				(font
					(size 1.016 1.016)
					(thickness 0.1524)
				)
				(justify mirror)
			)
		)
		(property "Device Type" "C805H58"
			(at 0.0762 -8.1534 180)
			(unlocked yes)
			(layer "B.Fab")
			(hide yes)
			(effects
				(font
					(size 1.016 1.016)
					(thickness 0.1524)
				)
				(justify mirror)
			)
		)
		(duplicate_pad_numbers_are_jumpers no)
		(fp_line
			(start -0.635 0)
			(end 0.635 0)
			(stroke
				(width 0.508)
				(type default)
			)
			(layer "B.SilkS")
		)
		(fp_rect
			(start 0.9652 1.778)
			(end -0.9652 -1.778)
			(stroke
				(width 0)
				(type default)
			)
			(fill no)
			(layer "B.CrtYd")
		)
		(fp_poly
			(pts
				(xy 0.9652 -1.778) (xy -0.9652 -1.778) (xy -0.9652 1.778) (xy 0.9652 1.778)
			)
			(stroke
				(width 0)
				(type default)
			)
			(fill no)
			(layer "B.Fab")
		)
		(pad "1" smd rect
			(at 0 -0.9652)
			(size 1.397 1.143)
			(layers "B.Cu" "B.Mask" "B.Paste")
			(net "P12V_B_4_VIN_U34")
		)
		(pad "2" smd rect
			(at 0 0.9652)
			(size 1.397 1.143)
			(layers "B.Cu" "B.Mask" "B.Paste")
			(net "GND")
		)
	)
	(footprint ""
		(layer "B.Cu")
		(at 27.184604 -229.626414 -90)
		(property "Reference" "R1106"
			(at 0 0 90)
			(layer "B.SilkS")
			(hide yes)
			(effects
				(font
					(size 1.27 1.27)
				)
				(justify mirror)
			)
		)
		(property "Value" "10R3F-GP"
			(at 0.0254 -2.5146 270)
			(unlocked yes)
			(layer "B.Fab")
			(hide yes)
			(effects
				(font
					(size 1.016 1.016)
					(thickness 0.1524)
				)
				(justify mirror)
			)
		)
		(property "Device Type" "R603H22"
			(at 0.0254 -4.0386 270)
			(unlocked yes)
			(layer "B.Fab")
			(hide yes)
			(effects
				(font
					(size 1.016 1.016)
					(thickness 0.1524)
				)
				(justify mirror)
			)
		)
		(duplicate_pad_numbers_are_jumpers no)
		(fp_line
			(start -0.2032 0)
			(end -0.4826 0)
			(stroke
				(width 0.2032)
				(type default)
			)
			(layer "B.SilkS")
		)
		(fp_line
			(start 0.4826 0)
			(end 0.2032 0)
			(stroke
				(width 0.2032)
				(type default)
			)
			(layer "B.SilkS")
		)
		(fp_rect
			(start 0.5842 1.3335)
			(end -0.5842 -1.3335)
			(stroke
				(width 0)
				(type default)
			)
			(fill no)
			(layer "B.CrtYd")
		)
		(fp_rect
			(start 0.5842 1.3335)
			(end -0.5842 -1.3335)
			(stroke
				(width 0)
				(type default)
			)
			(fill no)
			(layer "B.Fab")
		)
		(pad "1" smd custom
			(at 0 -0.762 90)
			(size 0.2159 0.2159)
			(layers "B.Cu" "B.Mask" "B.Paste")
			(net "P5V_B_1_CC")
			(options
				(clearance outline)
				(anchor circle)
			)
			(primitives
				(gr_poly
					(pts
						(arc
							(start -0.3302 0.4318)
							(mid -0.402042 0.402042)
							(end -0.4318 0.3302)
						)
						(arc
							(start -0.4318 -0.3302)
							(mid -0.402042 -0.402042)
							(end -0.3302 -0.4318)
						)
						(arc
							(start 0.3302 -0.4318)
							(mid 0.402042 -0.402042)
							(end 0.4318 -0.3302)
						)
						(arc
							(start 0.4318 0.3302)
							(mid 0.402042 0.402042)
							(end 0.3302 0.4318)
						)
					)
					(width 0)
					(fill yes)
				)
			)
		)
		(pad "2" smd custom
			(at 0 0.762 90)
			(size 0.2159 0.2159)
			(layers "B.Cu" "B.Mask" "B.Paste")
			(net "P5V_B_1_VFB_R")
			(options
				(clearance outline)
				(anchor circle)
			)
			(primitives
				(gr_poly
					(pts
						(arc
							(start -0.3302 0.4318)
							(mid -0.402042 0.402042)
							(end -0.4318 0.3302)
						)
						(arc
							(start -0.4318 -0.3302)
							(mid -0.402042 -0.402042)
							(end -0.3302 -0.4318)
						)
						(arc
							(start 0.3302 -0.4318)
							(mid 0.402042 -0.402042)
							(end 0.4318 -0.3302)
						)
						(arc
							(start 0.4318 0.3302)
							(mid 0.402042 0.402042)
							(end 0.3302 0.4318)
						)
					)
					(width 0)
					(fill yes)
				)
			)
		)
	)
)
